# T6G (Grand Teton) — schematic netlist excerpt (pin names and nets, part order shuffled) for the footprints in the layout excerpt that follows; sources: Cadence DE-HDL packaged netlist, KiCad conversion of 04192023_DAF0TMB3IC0_F0TG_MB_C_brd_V02_OCP.brd

R929  Q_RES  0 5% CHIP  pkg 0402LF  page 54 : A = CPU1_XTRIG_L4 ; B = CPU1_XTRIG_R1_L4
PC6526  Q_CAP  0.22UF 16V 10% X7R  pkg 0402  page 361 : A = SW_P1V8_RETIMER_CPU1_BST_R ; B = SW_P1V8_RETIMER_CPU1_SW
C705  Q_CAP_DIFFBUS  DIFF BUS_0.22UF 6.3V 20% X6S  pkg C0201  page 67 : \1\ = P5E_CPU1_G1_TX_C_DP<2> ; \2\ = P5E_CPU1_G1_TX_DP<2>

(kicad_pcb
	(version 20260206)
	(generator "pcbnew")
	(generator_version "10.0")
	(general
		(thickness 1.6)
		(legacy_teardrops no)
	)
	(paper "A4")
	(title_block
		(title "04192023_DAF0TMB3IC0_F0TG_MB_C_brd_V02_OCP.brd")
		(comment 1 "Grand Teton / footprints 1040-1042 of 8354")
	)
	(layers
		(0 "F.Cu" signal "TOP")
		(4 "In1.Cu" signal "GND")
		(6 "In2.Cu" signal "IN1")
		(8 "In3.Cu" signal "GND1")
		(10 "In4.Cu" signal "IN2")
		(12 "In5.Cu" signal "GND2")
		(14 "In6.Cu" signal "IN3")
		(16 "In7.Cu" signal "GND3")
		(18 "In8.Cu" signal "VCC")
		(20 "In9.Cu" signal "VCC1")
		(22 "In10.Cu" signal "GND4")
		(24 "In11.Cu" signal "IN4")
		(26 "In12.Cu" signal "GND5")
		(28 "In13.Cu" signal "IN5")
		(30 "In14.Cu" signal "GND6")
		(32 "In15.Cu" signal "IN6")
		(34 "In16.Cu" signal "GND7")
		(2 "B.Cu" signal "BOTTOM")
		(9 "F.Adhes" user "F.Adhesive")
		(11 "B.Adhes" user "B.Adhesive")
		(13 "F.Paste" user "Package Geometry/Pastemask Top")
		(15 "B.Paste" user "Package Geometry/Pastemask Bottom")
		(5 "F.SilkS" user "Ref Des/Silkscreen Top")
		(7 "B.SilkS" user "Ref Des/Silkscreen Bottom")
		(1 "F.Mask" user "Board Geometry/Soldermask Top")
		(3 "B.Mask" user "Board Geometry/Soldermask Bottom")
		(17 "Dwgs.User" user "User.Drawings")
		(19 "Cmts.User" user "User.Comments")
		(21 "Eco1.User" user "User.Eco1")
		(23 "Eco2.User" user "User.Eco2")
		(25 "Edge.Cuts" user "Board Geometry/Outline")
		(27 "Margin" user)
		(31 "F.CrtYd" user "Package Geometry/Place Bound Top")
		(29 "B.CrtYd" user "Package Geometry/Place Bound Bottom")
		(35 "F.Fab" user "Ref Des/Assembly Top")
		(33 "B.Fab" user "Ref Des/Assembly Bottom")
	)
	(footprint ""
		(layer "F.Cu")
		(at 4.410202 -58.863992 -90)
		(property "Reference" "R929"
			(at 0 0 270)
			(layer "F.SilkS")
			(hide yes)
			(effects
				(font
					(size 1.27 1.27)
				)
			)
		)
		(property "Value" ""
			(at 0 0 270)
			(layer "F.Fab")
			(effects
				(font
					(size 1.27 1.27)
				)
			)
		)
		(duplicate_pad_numbers_are_jumpers no)
		(fp_line
			(start -0.7874 0.4064)
			(end -0.7874 -0.4064)
			(stroke
				(width 0.1524)
				(type default)
			)
			(layer "F.SilkS")
		)
		(fp_line
			(start 0.7874 0.4064)
			(end -0.7874 0.4064)
			(stroke
				(width 0.1524)
				(type default)
			)
			(layer "F.SilkS")
		)
		(fp_line
			(start -0.7874 -0.4064)
			(end 0.7874 -0.4064)
			(stroke
				(width 0.1524)
				(type default)
			)
			(layer "F.SilkS")
		)
		(fp_line
			(start 0.7874 -0.4064)
			(end 0.7874 0.4064)
			(stroke
				(width 0.1524)
				(type default)
			)
			(layer "F.SilkS")
		)
		(fp_line
			(start -0.67945 0.3048)
			(end -0.67945 -0.305054)
			(stroke
				(width 0.1)
				(type default)
			)
			(layer "F.Fab")
		)
		(fp_line
			(start -0.12065 0.3048)
			(end -0.67945 0.3048)
			(stroke
				(width 0.1)
				(type default)
			)
			(layer "F.Fab")
		)
		(fp_line
			(start 0.120396 0.3048)
			(end 0.120396 0.2794)
			(stroke
				(width 0.1)
				(type default)
			)
			(layer "F.Fab")
		)
		(fp_line
			(start 0.67945 0.3048)
			(end 0.120396 0.3048)
			(stroke
				(width 0.1)
				(type default)
			)
			(layer "F.Fab")
		)
		(fp_line
			(start -0.12065 0.2794)
			(end -0.12065 0.3048)
			(stroke
				(width 0.1)
				(type default)
			)
			(layer "F.Fab")
		)
		(fp_line
			(start 0.120396 0.2794)
			(end -0.12065 0.2794)
			(stroke
				(width 0.1)
				(type default)
			)
			(layer "F.Fab")
		)
		(fp_line
			(start -0.12065 -0.2794)
			(end 0.12065 -0.2794)
			(stroke
				(width 0.1)
				(type default)
			)
			(layer "F.Fab")
		)
		(fp_line
			(start 0.12065 -0.2794)
			(end 0.12065 -0.3048)
			(stroke
				(width 0.1)
				(type default)
			)
			(layer "F.Fab")
		)
		(fp_line
			(start 0.12065 -0.3048)
			(end 0.67945 -0.3048)
			(stroke
				(width 0.1)
				(type default)
			)
			(layer "F.Fab")
		)
		(fp_line
			(start 0.67945 -0.3048)
			(end 0.67945 0.3048)
			(stroke
				(width 0.1)
				(type default)
			)
			(layer "F.Fab")
		)
		(fp_line
			(start -0.67945 -0.305054)
			(end -0.12065 -0.305054)
			(stroke
				(width 0.1)
				(type default)
			)
			(layer "F.Fab")
		)
		(fp_line
			(start -0.12065 -0.305054)
			(end -0.12065 -0.2794)
			(stroke
				(width 0.1)
				(type default)
			)
			(layer "F.Fab")
		)
		(pad "1" smd circle
			(at -0.40005 0 270)
			(size 0 0)
			(layers "F.Cu" "F.Mask" "F.Paste")
			(net "CPU1_XTRIG_L4")
		)
		(pad "2" smd circle
			(at 0.40005 0 270)
			(size 0 0)
			(layers "F.Cu" "F.Mask" "F.Paste")
			(net "CPU1_XTRIG_R1_L4")
		)
	)
	(footprint ""
		(layer "F.Cu")
		(at 53.08473 -17.623536 90)
		(property "Reference" "C705"
			(at 0 0 90)
			(layer "F.SilkS")
			(hide yes)
			(effects
				(font
					(size 1.27 1.27)
				)
			)
		)
		(property "Value" ""
			(at 0 0 90)
			(layer "F.Fab")
			(effects
				(font
					(size 1.27 1.27)
				)
			)
		)
		(duplicate_pad_numbers_are_jumpers no)
		(fp_line
			(start 0.299974 -0.150114)
			(end 0.299974 0.150114)
			(stroke
				(width 0.1)
				(type default)
			)
			(layer "F.Fab")
		)
		(fp_line
			(start -0.299974 -0.150114)
			(end 0.299974 -0.150114)
			(stroke
				(width 0.1)
				(type default)
			)
			(layer "F.Fab")
		)
		(fp_line
			(start 0.299974 0.150114)
			(end -0.299974 0.150114)
			(stroke
				(width 0.1)
				(type default)
			)
			(layer "F.Fab")
		)
		(fp_line
			(start -0.299974 0.150114)
			(end -0.299974 -0.150114)
			(stroke
				(width 0.1)
				(type default)
			)
			(layer "F.Fab")
		)
		(pad "1" smd rect
			(at -0.2667 0 90)
			(size 0.3048 0.381)
			(layers "F.Cu" "F.Mask" "F.Paste")
			(net "P5E_CPU1_G1_TX_C_DP<2>")
		)
		(pad "2" smd rect
			(at 0.2667 0 90)
			(size 0.3048 0.381)
			(layers "F.Cu" "F.Mask" "F.Paste")
			(net "P5E_CPU1_G1_TX_DP<2>")
		)
	)
	(footprint ""
		(layer "F.Cu")
		(at 227.430076 -294.978074 90)
		(property "Reference" "PC6526"
			(at 0 0 90)
			(layer "F.SilkS")
			(hide yes)
			(effects
				(font
					(size 1.27 1.27)
				)
			)
		)
		(property "Value" ""
			(at 0 0 90)
			(layer "F.Fab")
			(effects
				(font
					(size 1.27 1.27)
				)
			)
		)
		(duplicate_pad_numbers_are_jumpers no)
		(fp_line
			(start 0.7874 -0.4064)
			(end 0.7874 0.4064)
			(stroke
				(width 0.1524)
				(type default)
			)
			(layer "F.SilkS")
		)
		(fp_line
			(start -0.7874 -0.4064)
			(end 0.7874 -0.4064)
			(stroke
				(width 0.1524)
				(type default)
			)
			(layer "F.SilkS")
		)
		(fp_line
			(start 0.7874 0.4064)
			(end -0.7874 0.4064)
			(stroke
				(width 0.1524)
				(type default)
			)
			(layer "F.SilkS")
		)
		(fp_line
			(start -0.7874 0.4064)
			(end -0.7874 -0.4064)
			(stroke
				(width 0.1524)
				(type default)
			)
			(layer "F.SilkS")
		)
		(fp_line
			(start -0.12065 -0.305054)
			(end -0.12065 -0.2794)
			(stroke
				(width 0.1)
				(type default)
			)
			(layer "F.Fab")
		)
		(fp_line
			(start -0.67945 -0.305054)
			(end -0.12065 -0.305054)
			(stroke
				(width 0.1)
				(type default)
			)
			(layer "F.Fab")
		)
		(fp_line
			(start 0.67945 -0.3048)
			(end 0.67945 0.3048)
			(stroke
				(width 0.1)
				(type default)
			)
			(layer "F.Fab")
		)
		(fp_line
			(start 0.12065 -0.3048)
			(end 0.67945 -0.3048)
			(stroke
				(width 0.1)
				(type default)
			)
			(layer "F.Fab")
		)
		(fp_line
			(start 0.12065 -0.2794)
			(end 0.12065 -0.3048)
			(stroke
				(width 0.1)
				(type default)
			)
			(layer "F.Fab")
		)
		(fp_line
			(start -0.12065 -0.2794)
			(end 0.12065 -0.2794)
			(stroke
				(width 0.1)
				(type default)
			)
			(layer "F.Fab")
		)
		(fp_line
			(start 0.120396 0.2794)
			(end -0.12065 0.2794)
			(stroke
				(width 0.1)
				(type default)
			)
			(layer "F.Fab")
		)
		(fp_line
			(start -0.12065 0.2794)
			(end -0.12065 0.3048)
			(stroke
				(width 0.1)
				(type default)
			)
			(layer "F.Fab")
		)
		(fp_line
			(start 0.67945 0.3048)
			(end 0.120396 0.3048)
			(stroke
				(width 0.1)
				(type default)
			)
			(layer "F.Fab")
		)
		(fp_line
			(start 0.120396 0.3048)
			(end 0.120396 0.2794)
			(stroke
				(width 0.1)
				(type default)
			)
			(layer "F.Fab")
		)
		(fp_line
			(start -0.12065 0.3048)
			(end -0.67945 0.3048)
			(stroke
				(width 0.1)
				(type default)
			)
			(layer "F.Fab")
		)
		(fp_line
			(start -0.67945 0.3048)
			(end -0.67945 -0.305054)
			(stroke
				(width 0.1)
				(type default)
			)
			(layer "F.Fab")
		)
		(pad "1" smd circle
			(at -0.40005 0 90)
			(size 0 0)
			(layers "F.Cu" "F.Mask" "F.Paste")
			(net "SW_P1V8_RETIMER_CPU1_BST_R")
		)
		(pad "2" smd circle
			(at 0.40005 0 90)
			(size 0 0)
			(layers "F.Cu" "F.Mask" "F.Paste")
			(net "SW_P1V8_RETIMER_CPU1_SW")
		)
	)
)
